# T6G (Grand Teton) — schematic netlist excerpt (pin names and nets, part order shuffled) for the footprints in the layout excerpt that follows; sources: Cadence DE-HDL packaged netlist, KiCad conversion of 04192023_DAF0TMB3IC0_F0TG_MB_C_brd_V02_OCP.brd

H101  HOLE  EMPTY  pkg TH  page 230 : \1\ = GND
H92  HOLE  EMPTY  pkg TH  page 230 : \1\ = GND
R3715  Q_RES  0 5% CHIP  pkg 0402LF  page 252 : A = SMB_LM75_0_3V3AUX_SCL_R ; B = SMB_LM75_0_3V3AUX_SCL
PR321  Q_RES  8.87K 1% EMPTY  pkg 0402LF  page 194 : A = GND ; B = PVDDCR_CPU0_P0_LSET2

(kicad_pcb
	(version 20260206)
	(generator "pcbnew")
	(generator_version "10.0")
	(general
		(thickness 1.6)
		(legacy_teardrops no)
	)
	(paper "A4")
	(title_block
		(title "04192023_DAF0TMB3IC0_F0TG_MB_C_brd_V02_OCP.brd")
		(comment 1 "Grand Teton / footprints 3986-3989 of 8354")
	)
	(layers
		(0 "F.Cu" signal "TOP")
		(4 "In1.Cu" signal "GND")
		(6 "In2.Cu" signal "IN1")
		(8 "In3.Cu" signal "GND1")
		(10 "In4.Cu" signal "IN2")
		(12 "In5.Cu" signal "GND2")
		(14 "In6.Cu" signal "IN3")
		(16 "In7.Cu" signal "GND3")
		(18 "In8.Cu" signal "VCC")
		(20 "In9.Cu" signal "VCC1")
		(22 "In10.Cu" signal "GND4")
		(24 "In11.Cu" signal "IN4")
		(26 "In12.Cu" signal "GND5")
		(28 "In13.Cu" signal "IN5")
		(30 "In14.Cu" signal "GND6")
		(32 "In15.Cu" signal "IN6")
		(34 "In16.Cu" signal "GND7")
		(2 "B.Cu" signal "BOTTOM")
		(9 "F.Adhes" user "F.Adhesive")
		(11 "B.Adhes" user "B.Adhesive")
		(13 "F.Paste" user "Package Geometry/Pastemask Top")
		(15 "B.Paste" user "Package Geometry/Pastemask Bottom")
		(5 "F.SilkS" user "Ref Des/Silkscreen Top")
		(7 "B.SilkS" user "Ref Des/Silkscreen Bottom")
		(1 "F.Mask" user "Board Geometry/Soldermask Top")
		(3 "B.Mask" user "Board Geometry/Soldermask Bottom")
		(17 "Dwgs.User" user "User.Drawings")
		(19 "Cmts.User" user "User.Comments")
		(21 "Eco1.User" user "User.Eco1")
		(23 "Eco2.User" user "User.Eco2")
		(25 "Edge.Cuts" user "Board Geometry/Outline")
		(27 "Margin" user)
		(31 "F.CrtYd" user "Package Geometry/Place Bound Top")
		(29 "B.CrtYd" user "Package Geometry/Place Bound Bottom")
		(35 "F.Fab" user "Ref Des/Assembly Top")
		(33 "B.Fab" user "Ref Des/Assembly Bottom")
	)
	(footprint ""
		(layer "F.Cu")
		(at 373.979694 -177.532284)
		(property "Reference" "PR321"
			(at 0 0 0)
			(layer "F.SilkS")
			(hide yes)
			(effects
				(font
					(size 1.27 1.27)
				)
			)
		)
		(property "Value" ""
			(at 0 0 0)
			(layer "F.Fab")
			(effects
				(font
					(size 1.27 1.27)
				)
			)
		)
		(duplicate_pad_numbers_are_jumpers no)
		(fp_line
			(start -0.7874 -0.4064)
			(end 0.7874 -0.4064)
			(stroke
				(width 0.1524)
				(type default)
			)
			(layer "F.SilkS")
		)
		(fp_line
			(start -0.7874 0.4064)
			(end -0.7874 -0.4064)
			(stroke
				(width 0.1524)
				(type default)
			)
			(layer "F.SilkS")
		)
		(fp_line
			(start 0.7874 -0.4064)
			(end 0.7874 0.4064)
			(stroke
				(width 0.1524)
				(type default)
			)
			(layer "F.SilkS")
		)
		(fp_line
			(start 0.7874 0.4064)
			(end -0.7874 0.4064)
			(stroke
				(width 0.1524)
				(type default)
			)
			(layer "F.SilkS")
		)
		(fp_line
			(start -0.67945 -0.305054)
			(end -0.12065 -0.305054)
			(stroke
				(width 0.1)
				(type default)
			)
			(layer "F.Fab")
		)
		(fp_line
			(start -0.67945 0.3048)
			(end -0.67945 -0.305054)
			(stroke
				(width 0.1)
				(type default)
			)
			(layer "F.Fab")
		)
		(fp_line
			(start -0.12065 -0.305054)
			(end -0.12065 -0.2794)
			(stroke
				(width 0.1)
				(type default)
			)
			(layer "F.Fab")
		)
		(fp_line
			(start -0.12065 -0.2794)
			(end 0.12065 -0.2794)
			(stroke
				(width 0.1)
				(type default)
			)
			(layer "F.Fab")
		)
		(fp_line
			(start -0.12065 0.2794)
			(end -0.12065 0.3048)
			(stroke
				(width 0.1)
				(type default)
			)
			(layer "F.Fab")
		)
		(fp_line
			(start -0.12065 0.3048)
			(end -0.67945 0.3048)
			(stroke
				(width 0.1)
				(type default)
			)
			(layer "F.Fab")
		)
		(fp_line
			(start 0.120396 0.2794)
			(end -0.12065 0.2794)
			(stroke
				(width 0.1)
				(type default)
			)
			(layer "F.Fab")
		)
		(fp_line
			(start 0.120396 0.3048)
			(end 0.120396 0.2794)
			(stroke
				(width 0.1)
				(type default)
			)
			(layer "F.Fab")
		)
		(fp_line
			(start 0.12065 -0.3048)
			(end 0.67945 -0.3048)
			(stroke
				(width 0.1)
				(type default)
			)
			(layer "F.Fab")
		)
		(fp_line
			(start 0.12065 -0.2794)
			(end 0.12065 -0.3048)
			(stroke
				(width 0.1)
				(type default)
			)
			(layer "F.Fab")
		)
		(fp_line
			(start 0.67945 -0.3048)
			(end 0.67945 0.3048)
			(stroke
				(width 0.1)
				(type default)
			)
			(layer "F.Fab")
		)
		(fp_line
			(start 0.67945 0.3048)
			(end 0.120396 0.3048)
			(stroke
				(width 0.1)
				(type default)
			)
			(layer "F.Fab")
		)
		(pad "1" smd circle
			(at -0.40005 0)
			(size 0 0)
			(layers "F.Cu" "F.Mask" "F.Paste")
			(net "GND")
		)
		(pad "2" smd circle
			(at 0.40005 0)
			(size 0 0)
			(layers "F.Cu" "F.Mask" "F.Paste")
			(net "PVDDCR_CPU0_P0_LSET2")
		)
	)
	(footprint ""
		(layer "F.Cu")
		(at 257.242056 -118.91137 180)
		(property "Reference" "R3715"
			(at 0 0 180)
			(layer "F.SilkS")
			(hide yes)
			(effects
				(font
					(size 1.27 1.27)
				)
			)
		)
		(property "Value" ""
			(at 0 0 180)
			(layer "F.Fab")
			(effects
				(font
					(size 1.27 1.27)
				)
			)
		)
		(duplicate_pad_numbers_are_jumpers no)
		(fp_line
			(start 0.7874 0.4064)
			(end -0.7874 0.4064)
			(stroke
				(width 0.1524)
				(type default)
			)
			(layer "F.SilkS")
		)
		(fp_line
			(start 0.7874 -0.4064)
			(end 0.7874 0.4064)
			(stroke
				(width 0.1524)
				(type default)
			)
			(layer "F.SilkS")
		)
		(fp_line
			(start -0.7874 0.4064)
			(end -0.7874 -0.4064)
			(stroke
				(width 0.1524)
				(type default)
			)
			(layer "F.SilkS")
		)
		(fp_line
			(start -0.7874 -0.4064)
			(end 0.7874 -0.4064)
			(stroke
				(width 0.1524)
				(type default)
			)
			(layer "F.SilkS")
		)
		(fp_line
			(start 0.67945 0.3048)
			(end 0.120396 0.3048)
			(stroke
				(width 0.1)
				(type default)
			)
			(layer "F.Fab")
		)
		(fp_line
			(start 0.67945 -0.3048)
			(end 0.67945 0.3048)
			(stroke
				(width 0.1)
				(type default)
			)
			(layer "F.Fab")
		)
		(fp_line
			(start 0.12065 -0.2794)
			(end 0.12065 -0.3048)
			(stroke
				(width 0.1)
				(type default)
			)
			(layer "F.Fab")
		)
		(fp_line
			(start 0.12065 -0.3048)
			(end 0.67945 -0.3048)
			(stroke
				(width 0.1)
				(type default)
			)
			(layer "F.Fab")
		)
		(fp_line
			(start 0.120396 0.3048)
			(end 0.120396 0.2794)
			(stroke
				(width 0.1)
				(type default)
			)
			(layer "F.Fab")
		)
		(fp_line
			(start 0.120396 0.2794)
			(end -0.12065 0.2794)
			(stroke
				(width 0.1)
				(type default)
			)
			(layer "F.Fab")
		)
		(fp_line
			(start -0.12065 0.3048)
			(end -0.67945 0.3048)
			(stroke
				(width 0.1)
				(type default)
			)
			(layer "F.Fab")
		)
		(fp_line
			(start -0.12065 0.2794)
			(end -0.12065 0.3048)
			(stroke
				(width 0.1)
				(type default)
			)
			(layer "F.Fab")
		)
		(fp_line
			(start -0.12065 -0.2794)
			(end 0.12065 -0.2794)
			(stroke
				(width 0.1)
				(type default)
			)
			(layer "F.Fab")
		)
		(fp_line
			(start -0.12065 -0.305054)
			(end -0.12065 -0.2794)
			(stroke
				(width 0.1)
				(type default)
			)
			(layer "F.Fab")
		)
		(fp_line
			(start -0.67945 0.3048)
			(end -0.67945 -0.305054)
			(stroke
				(width 0.1)
				(type default)
			)
			(layer "F.Fab")
		)
		(fp_line
			(start -0.67945 -0.305054)
			(end -0.12065 -0.305054)
			(stroke
				(width 0.1)
				(type default)
			)
			(layer "F.Fab")
		)
		(pad "1" smd circle
			(at -0.40005 0 180)
			(size 0 0)
			(layers "F.Cu" "F.Mask" "F.Paste")
			(net "SMB_LM75_0_3V3AUX_SCL_R")
		)
		(pad "2" smd circle
			(at 0.40005 0 180)
			(size 0 0)
			(layers "F.Cu" "F.Mask" "F.Paste")
			(net "SMB_LM75_0_3V3AUX_SCL")
		)
	)
	(footprint ""
		(layer "F.Cu")
		(at 203.399898 -22.29993)
		(property "Reference" "H92"
			(at -5.458206 -6.02488 0)
			(unlocked yes)
			(layer "F.SilkS")
			(effects
				(font
					(size 0.7874 0.5842)
					(thickness 0.1524)
				)
				(justify left)
			)
		)
		(property "Value" ""
			(at 0 0 0)
			(layer "F.Fab")
			(effects
				(font
					(size 1.27 1.27)
				)
			)
		)
		(duplicate_pad_numbers_are_jumpers no)
		(pad "1" thru_hole circle
			(at 0 0)
			(size 10.0076 10.0076)
			(drill 5.6134)
			(layers "*.Cu" "*.Mask")
			(remove_unused_layers no)
			(net "GND")
			(clearance -1.9431)
		)
	)
	(footprint ""
		(layer "F.Cu")
		(at 322.90004 -160.50006)
		(property "Reference" "H101"
			(at -5.698998 -5.882386 0)
			(unlocked yes)
			(layer "F.SilkS")
			(effects
				(font
					(size 0.7874 0.5842)
					(thickness 0.1524)
				)
				(justify left)
			)
		)
		(property "Value" ""
			(at 0 0 0)
			(layer "F.Fab")
			(effects
				(font
					(size 1.27 1.27)
				)
			)
		)
		(duplicate_pad_numbers_are_jumpers no)
		(pad "1" thru_hole circle
			(at 0 0)
			(size 10.0076 10.0076)
			(drill 5.6134)
			(layers "*.Cu" "*.Mask")
			(remove_unused_layers no)
			(net "GND")
			(clearance -1.9431)
		)
	)
)
